(kicad_pcb
	(version 20260206)
	(generator "pcbnew")
	(generator_version "10.0")
	(general
		(thickness 1.6)
		(legacy_teardrops no)
	)
	(paper "A4")
	(title_block
		(title "04192023_DAF0TMB3IC0_F0TG_MB_C_brd_V02_OCP.brd")
		(comment 1 "Grand Teton / footprints 5472-5478 of 8354")
	)
	(layers
		(0 "F.Cu" signal "TOP")
		(4 "In1.Cu" signal "GND")
		(6 "In2.Cu" signal "IN1")
		(8 "In3.Cu" signal "GND1")
		(10 "In4.Cu" signal "IN2")
		(12 "In5.Cu" signal "GND2")
		(14 "In6.Cu" signal "IN3")
		(16 "In7.Cu" signal "GND3")
		(18 "In8.Cu" signal "VCC")
		(20 "In9.Cu" signal "VCC1")
		(22 "In10.Cu" signal "GND4")
		(24 "In11.Cu" signal "IN4")
		(26 "In12.Cu" signal "GND5")
		(28 "In13.Cu" signal "IN5")
		(30 "In14.Cu" signal "GND6")
		(32 "In15.Cu" signal "IN6")
		(34 "In16.Cu" signal "GND7")
		(2 "B.Cu" signal "BOTTOM")
		(9 "F.Adhes" user "F.Adhesive")
		(11 "B.Adhes" user "B.Adhesive")
		(13 "F.Paste" user "Package Geometry/Pastemask Top")
		(15 "B.Paste" user "Package Geometry/Pastemask Bottom")
		(5 "F.SilkS" user "Ref Des/Silkscreen Top")
		(7 "B.SilkS" user "Ref Des/Silkscreen Bottom")
		(1 "F.Mask" user "Board Geometry/Soldermask Top")
		(3 "B.Mask" user "Board Geometry/Soldermask Bottom")
		(17 "Dwgs.User" user "User.Drawings")
		(19 "Cmts.User" user "User.Comments")
		(21 "Eco1.User" user "User.Eco1")
		(23 "Eco2.User" user "User.Eco2")
		(25 "Edge.Cuts" user "Board Geometry/Outline")
		(27 "Margin" user)
		(31 "F.CrtYd" user "Package Geometry/Place Bound Top")
		(29 "B.CrtYd" user "Package Geometry/Place Bound Bottom")
		(35 "F.Fab" user "Ref Des/Assembly Top")
		(33 "B.Fab" user "Ref Des/Assembly Bottom")
	)
	(footprint ""
		(layer "B.Cu")
		(at 371.691154 -398.942052 90)
		(property "Reference" "C1030"
			(at 0 0 90)
			(layer "B.SilkS")
			(hide yes)
			(effects
				(font
					(size 1.27 1.27)
				)
				(justify mirror)
			)
		)
		(property "Value" ""
			(at 0 0 90)
			(layer "B.Fab")
			(effects
				(font
					(size 1.27 1.27)
				)
				(justify mirror)
			)
		)
		(duplicate_pad_numbers_are_jumpers no)
		(fp_line
			(start 0.7874 -0.4064)
			(end -0.7874 -0.4064)
			(stroke
				(width 0.1524)
				(type default)
			)
			(layer "B.SilkS")
		)
		(fp_line
			(start -0.7874 -0.4064)
			(end -0.7874 0.4064)
			(stroke
				(width 0.1524)
				(type default)
			)
			(layer "B.SilkS")
		)
		(fp_line
			(start 0.7874 0.4064)
			(end 0.7874 -0.4064)
			(stroke
				(width 0.1524)
				(type default)
			)
			(layer "B.SilkS")
		)
		(fp_line
			(start -0.7874 0.4064)
			(end 0.7874 0.4064)
			(stroke
				(width 0.1524)
				(type default)
			)
			(layer "B.SilkS")
		)
		(fp_line
			(start 0.67945 -0.305054)
			(end 0.12065 -0.305054)
			(stroke
				(width 0.1)
				(type default)
			)
			(layer "B.Fab")
		)
		(fp_line
			(start 0.12065 -0.305054)
			(end 0.12065 -0.2794)
			(stroke
				(width 0.1)
				(type default)
			)
			(layer "B.Fab")
		)
		(fp_line
			(start -0.12065 -0.3048)
			(end -0.67945 -0.3048)
			(stroke
				(width 0.1)
				(type default)
			)
			(layer "B.Fab")
		)
		(fp_line
			(start -0.67945 -0.3048)
			(end -0.67945 0.3048)
			(stroke
				(width 0.1)
				(type default)
			)
			(layer "B.Fab")
		)
		(fp_line
			(start 0.12065 -0.2794)
			(end -0.12065 -0.2794)
			(stroke
				(width 0.1)
				(type default)
			)
			(layer "B.Fab")
		)
		(fp_line
			(start -0.12065 -0.2794)
			(end -0.12065 -0.3048)
			(stroke
				(width 0.1)
				(type default)
			)
			(layer "B.Fab")
		)
		(fp_line
			(start 0.12065 0.2794)
			(end 0.12065 0.3048)
			(stroke
				(width 0.1)
				(type default)
			)
			(layer "B.Fab")
		)
		(fp_line
			(start -0.120396 0.2794)
			(end 0.12065 0.2794)
			(stroke
				(width 0.1)
				(type default)
			)
			(layer "B.Fab")
		)
		(fp_line
			(start 0.67945 0.3048)
			(end 0.67945 -0.305054)
			(stroke
				(width 0.1)
				(type default)
			)
			(layer "B.Fab")
		)
		(fp_line
			(start 0.12065 0.3048)
			(end 0.67945 0.3048)
			(stroke
				(width 0.1)
				(type default)
			)
			(layer "B.Fab")
		)
		(fp_line
			(start -0.120396 0.3048)
			(end -0.120396 0.2794)
			(stroke
				(width 0.1)
				(type default)
			)
			(layer "B.Fab")
		)
		(fp_line
			(start -0.67945 0.3048)
			(end -0.120396 0.3048)
			(stroke
				(width 0.1)
				(type default)
			)
			(layer "B.Fab")
		)
		(pad "1" smd circle
			(at 0.40005 0 270)
			(size 0 0)
			(layers "B.Cu" "B.Mask" "B.Paste")
			(net "P0V9_CPU0_RT3_2A")
		)
		(pad "2" smd circle
			(at -0.40005 0 270)
			(size 0 0)
			(layers "B.Cu" "B.Mask" "B.Paste")
			(net "GND")
		)
	)
	(footprint ""
		(layer "B.Cu")
		(at 125.389386 -254.194564)
		(property "Reference" "C2452"
			(at 0 0 0)
			(layer "B.SilkS")
			(hide yes)
			(effects
				(font
					(size 1.27 1.27)
				)
				(justify mirror)
			)
		)
		(property "Value" ""
			(at 0 0 0)
			(layer "B.Fab")
			(effects
				(font
					(size 1.27 1.27)
				)
				(justify mirror)
			)
		)
		(duplicate_pad_numbers_are_jumpers no)
		(fp_line
			(start -0.7874 -0.4064)
			(end -0.7874 0.4064)
			(stroke
				(width 0.1524)
				(type default)
			)
			(layer "B.SilkS")
		)
		(fp_line
			(start -0.7874 0.4064)
			(end 0.7874 0.4064)
			(stroke
				(width 0.1524)
				(type default)
			)
			(layer "B.SilkS")
		)
		(fp_line
			(start 0.7874 -0.4064)
			(end -0.7874 -0.4064)
			(stroke
				(width 0.1524)
				(type default)
			)
			(layer "B.SilkS")
		)
		(fp_line
			(start 0.7874 0.4064)
			(end 0.7874 -0.4064)
			(stroke
				(width 0.1524)
				(type default)
			)
			(layer "B.SilkS")
		)
		(fp_line
			(start -0.67945 -0.3048)
			(end -0.67945 0.3048)
			(stroke
				(width 0.1)
				(type default)
			)
			(layer "B.Fab")
		)
		(fp_line
			(start -0.67945 0.3048)
			(end -0.120396 0.3048)
			(stroke
				(width 0.1)
				(type default)
			)
			(layer "B.Fab")
		)
		(fp_line
			(start -0.12065 -0.3048)
			(end -0.67945 -0.3048)
			(stroke
				(width 0.1)
				(type default)
			)
			(layer "B.Fab")
		)
		(fp_line
			(start -0.12065 -0.2794)
			(end -0.12065 -0.3048)
			(stroke
				(width 0.1)
				(type default)
			)
			(layer "B.Fab")
		)
		(fp_line
			(start -0.120396 0.2794)
			(end 0.12065 0.2794)
			(stroke
				(width 0.1)
				(type default)
			)
			(layer "B.Fab")
		)
		(fp_line
			(start -0.120396 0.3048)
			(end -0.120396 0.2794)
			(stroke
				(width 0.1)
				(type default)
			)
			(layer "B.Fab")
		)
		(fp_line
			(start 0.12065 -0.305054)
			(end 0.12065 -0.2794)
			(stroke
				(width 0.1)
				(type default)
			)
			(layer "B.Fab")
		)
		(fp_line
			(start 0.12065 -0.2794)
			(end -0.12065 -0.2794)
			(stroke
				(width 0.1)
				(type default)
			)
			(layer "B.Fab")
		)
		(fp_line
			(start 0.12065 0.2794)
			(end 0.12065 0.3048)
			(stroke
				(width 0.1)
				(type default)
			)
			(layer "B.Fab")
		)
		(fp_line
			(start 0.12065 0.3048)
			(end 0.67945 0.3048)
			(stroke
				(width 0.1)
				(type default)
			)
			(layer "B.Fab")
		)
		(fp_line
			(start 0.67945 -0.305054)
			(end 0.12065 -0.305054)
			(stroke
				(width 0.1)
				(type default)
			)
			(layer "B.Fab")
		)
		(fp_line
			(start 0.67945 0.3048)
			(end 0.67945 -0.305054)
			(stroke
				(width 0.1)
				(type default)
			)
			(layer "B.Fab")
		)
		(pad "1" smd circle
			(at 0.40005 0 180)
			(size 0 0)
			(layers "B.Cu" "B.Mask" "B.Paste")
			(net "PVDDCR_SOC_P1")
		)
		(pad "2" smd circle
			(at -0.40005 0 180)
			(size 0 0)
			(layers "B.Cu" "B.Mask" "B.Paste")
			(net "GND")
		)
	)
	(footprint ""
		(layer "B.Cu")
		(at 372.937278 -142.488158)
		(property "Reference" "PC466"
			(at 0 0 0)
			(layer "B.SilkS")
			(hide yes)
			(effects
				(font
					(size 1.27 1.27)
				)
				(justify mirror)
			)
		)
		(property "Value" ""
			(at 0 0 0)
			(layer "B.Fab")
			(effects
				(font
					(size 1.27 1.27)
				)
				(justify mirror)
			)
		)
		(duplicate_pad_numbers_are_jumpers no)
		(fp_line
			(start -0.7874 -0.4064)
			(end -0.7874 0.4064)
			(stroke
				(width 0.1524)
				(type default)
			)
			(layer "B.SilkS")
		)
		(fp_line
			(start -0.7874 0.4064)
			(end 0.7874 0.4064)
			(stroke
				(width 0.1524)
				(type default)
			)
			(layer "B.SilkS")
		)
		(fp_line
			(start 0.7874 -0.4064)
			(end -0.7874 -0.4064)
			(stroke
				(width 0.1524)
				(type default)
			)
			(layer "B.SilkS")
		)
		(fp_line
			(start 0.7874 0.4064)
			(end 0.7874 -0.4064)
			(stroke
				(width 0.1524)
				(type default)
			)
			(layer "B.SilkS")
		)
		(fp_line
			(start -0.67945 -0.3048)
			(end -0.67945 0.3048)
			(stroke
				(width 0.1)
				(type default)
			)
			(layer "B.Fab")
		)
		(fp_line
			(start -0.67945 0.3048)
			(end -0.120396 0.3048)
			(stroke
				(width 0.1)
				(type default)
			)
			(layer "B.Fab")
		)
		(fp_line
			(start -0.12065 -0.3048)
			(end -0.67945 -0.3048)
			(stroke
				(width 0.1)
				(type default)
			)
			(layer "B.Fab")
		)
		(fp_line
			(start -0.12065 -0.2794)
			(end -0.12065 -0.3048)
			(stroke
				(width 0.1)
				(type default)
			)
			(layer "B.Fab")
		)
		(fp_line
			(start -0.120396 0.2794)
			(end 0.12065 0.2794)
			(stroke
				(width 0.1)
				(type default)
			)
			(layer "B.Fab")
		)
		(fp_line
			(start -0.120396 0.3048)
			(end -0.120396 0.2794)
			(stroke
				(width 0.1)
				(type default)
			)
			(layer "B.Fab")
		)
		(fp_line
			(start 0.12065 -0.305054)
			(end 0.12065 -0.2794)
			(stroke
				(width 0.1)
				(type default)
			)
			(layer "B.Fab")
		)
		(fp_line
			(start 0.12065 -0.2794)
			(end -0.12065 -0.2794)
			(stroke
				(width 0.1)
				(type default)
			)
			(layer "B.Fab")
		)
		(fp_line
			(start 0.12065 0.2794)
			(end 0.12065 0.3048)
			(stroke
				(width 0.1)
				(type default)
			)
			(layer "B.Fab")
		)
		(fp_line
			(start 0.12065 0.3048)
			(end 0.67945 0.3048)
			(stroke
				(width 0.1)
				(type default)
			)
			(layer "B.Fab")
		)
		(fp_line
			(start 0.67945 -0.305054)
			(end 0.12065 -0.305054)
			(stroke
				(width 0.1)
				(type default)
			)
			(layer "B.Fab")
		)
		(fp_line
			(start 0.67945 0.3048)
			(end 0.67945 -0.305054)
			(stroke
				(width 0.1)
				(type default)
			)
			(layer "B.Fab")
		)
		(pad "1" smd circle
			(at 0.40005 0 180)
			(size 0 0)
			(layers "B.Cu" "B.Mask" "B.Paste")
			(net "PVDD18_S5_P0")
		)
		(pad "2" smd circle
			(at -0.40005 0 180)
			(size 0 0)
			(layers "B.Cu" "B.Mask" "B.Paste")
			(net "GND")
		)
	)
	(footprint ""
		(layer "B.Cu")
		(at 144.3228 -13.765022 90)
		(property "Reference" "R6033"
			(at 0 0 90)
			(layer "B.SilkS")
			(hide yes)
			(effects
				(font
					(size 1.27 1.27)
				)
				(justify mirror)
			)
		)
		(property "Value" ""
			(at 0 0 90)
			(layer "B.Fab")
			(effects
				(font
					(size 1.27 1.27)
				)
				(justify mirror)
			)
		)
		(duplicate_pad_numbers_are_jumpers no)
		(fp_line
			(start 0.7874 -0.4064)
			(end -0.7874 -0.4064)
			(stroke
				(width 0.1524)
				(type default)
			)
			(layer "B.SilkS")
		)
		(fp_line
			(start -0.7874 -0.4064)
			(end -0.7874 0.4064)
			(stroke
				(width 0.1524)
				(type default)
			)
			(layer "B.SilkS")
		)
		(fp_line
			(start 0.7874 0.4064)
			(end 0.7874 -0.4064)
			(stroke
				(width 0.1524)
				(type default)
			)
			(layer "B.SilkS")
		)
		(fp_line
			(start -0.7874 0.4064)
			(end 0.7874 0.4064)
			(stroke
				(width 0.1524)
				(type default)
			)
			(layer "B.SilkS")
		)
		(fp_line
			(start 0.67945 -0.305054)
			(end 0.12065 -0.305054)
			(stroke
				(width 0.1)
				(type default)
			)
			(layer "B.Fab")
		)
		(fp_line
			(start 0.12065 -0.305054)
			(end 0.12065 -0.2794)
			(stroke
				(width 0.1)
				(type default)
			)
			(layer "B.Fab")
		)
		(fp_line
			(start -0.12065 -0.3048)
			(end -0.67945 -0.3048)
			(stroke
				(width 0.1)
				(type default)
			)
			(layer "B.Fab")
		)
		(fp_line
			(start -0.67945 -0.3048)
			(end -0.67945 0.3048)
			(stroke
				(width 0.1)
				(type default)
			)
			(layer "B.Fab")
		)
		(fp_line
			(start 0.12065 -0.2794)
			(end -0.12065 -0.2794)
			(stroke
				(width 0.1)
				(type default)
			)
			(layer "B.Fab")
		)
		(fp_line
			(start -0.12065 -0.2794)
			(end -0.12065 -0.3048)
			(stroke
				(width 0.1)
				(type default)
			)
			(layer "B.Fab")
		)
		(fp_line
			(start 0.12065 0.2794)
			(end 0.12065 0.3048)
			(stroke
				(width 0.1)
				(type default)
			)
			(layer "B.Fab")
		)
		(fp_line
			(start -0.120396 0.2794)
			(end 0.12065 0.2794)
			(stroke
				(width 0.1)
				(type default)
			)
			(layer "B.Fab")
		)
		(fp_line
			(start 0.67945 0.3048)
			(end 0.67945 -0.305054)
			(stroke
				(width 0.1)
				(type default)
			)
			(layer "B.Fab")
		)
		(fp_line
			(start 0.12065 0.3048)
			(end 0.67945 0.3048)
			(stroke
				(width 0.1)
				(type default)
			)
			(layer "B.Fab")
		)
		(fp_line
			(start -0.120396 0.3048)
			(end -0.120396 0.2794)
			(stroke
				(width 0.1)
				(type default)
			)
			(layer "B.Fab")
		)
		(fp_line
			(start -0.67945 0.3048)
			(end -0.120396 0.3048)
			(stroke
				(width 0.1)
				(type default)
			)
			(layer "B.Fab")
		)
		(pad "1" smd circle
			(at 0.40005 0 270)
			(size 0 0)
			(layers "B.Cu" "B.Mask" "B.Paste")
			(net "RST_MB_STBY_N")
		)
		(pad "2" smd circle
			(at -0.40005 0 270)
			(size 0 0)
			(layers "B.Cu" "B.Mask" "B.Paste")
			(net "RST_MB_STBY_R_N")
		)
	)
	(footprint ""
		(layer "B.Cu")
		(at 288.200846 -420.38143 90)
		(property "Reference" "C2329"
			(at 0 0 90)
			(layer "B.SilkS")
			(hide yes)
			(effects
				(font
					(size 1.27 1.27)
				)
				(justify mirror)
			)
		)
		(property "Value" ""
			(at 0 0 90)
			(layer "B.Fab")
			(effects
				(font
					(size 1.27 1.27)
				)
				(justify mirror)
			)
		)
		(duplicate_pad_numbers_are_jumpers no)
		(fp_line
			(start 0.7874 -0.4064)
			(end -0.7874 -0.4064)
			(stroke
				(width 0.1524)
				(type default)
			)
			(layer "B.SilkS")
		)
		(fp_line
			(start -0.7874 -0.4064)
			(end -0.7874 0.4064)
			(stroke
				(width 0.1524)
				(type default)
			)
			(layer "B.SilkS")
		)
		(fp_line
			(start 0.7874 0.4064)
			(end 0.7874 -0.4064)
			(stroke
				(width 0.1524)
				(type default)
			)
			(layer "B.SilkS")
		)
		(fp_line
			(start -0.7874 0.4064)
			(end 0.7874 0.4064)
			(stroke
				(width 0.1524)
				(type default)
			)
			(layer "B.SilkS")
		)
		(fp_line
			(start 0.67945 -0.305054)
			(end 0.12065 -0.305054)
			(stroke
				(width 0.1)
				(type default)
			)
			(layer "B.Fab")
		)
		(fp_line
			(start 0.12065 -0.305054)
			(end 0.12065 -0.2794)
			(stroke
				(width 0.1)
				(type default)
			)
			(layer "B.Fab")
		)
		(fp_line
			(start -0.12065 -0.3048)
			(end -0.67945 -0.3048)
			(stroke
				(width 0.1)
				(type default)
			)
			(layer "B.Fab")
		)
		(fp_line
			(start -0.67945 -0.3048)
			(end -0.67945 0.3048)
			(stroke
				(width 0.1)
				(type default)
			)
			(layer "B.Fab")
		)
		(fp_line
			(start 0.12065 -0.2794)
			(end -0.12065 -0.2794)
			(stroke
				(width 0.1)
				(type default)
			)
			(layer "B.Fab")
		)
		(fp_line
			(start -0.12065 -0.2794)
			(end -0.12065 -0.3048)
			(stroke
				(width 0.1)
				(type default)
			)
			(layer "B.Fab")
		)
		(fp_line
			(start 0.12065 0.2794)
			(end 0.12065 0.3048)
			(stroke
				(width 0.1)
				(type default)
			)
			(layer "B.Fab")
		)
		(fp_line
			(start -0.120396 0.2794)
			(end 0.12065 0.2794)
			(stroke
				(width 0.1)
				(type default)
			)
			(layer "B.Fab")
		)
		(fp_line
			(start 0.67945 0.3048)
			(end 0.67945 -0.305054)
			(stroke
				(width 0.1)
				(type default)
			)
			(layer "B.Fab")
		)
		(fp_line
			(start 0.12065 0.3048)
			(end 0.67945 0.3048)
			(stroke
				(width 0.1)
				(type default)
			)
			(layer "B.Fab")
		)
		(fp_line
			(start -0.120396 0.3048)
			(end -0.120396 0.2794)
			(stroke
				(width 0.1)
				(type default)
			)
			(layer "B.Fab")
		)
		(fp_line
			(start -0.67945 0.3048)
			(end -0.120396 0.3048)
			(stroke
				(width 0.1)
				(type default)
			)
			(layer "B.Fab")
		)
		(pad "1" smd circle
			(at 0.40005 0 270)
			(size 0 0)
			(layers "B.Cu" "B.Mask" "B.Paste")
			(net "P3V3_9ZXL045_P0_VDD")
		)
		(pad "2" smd circle
			(at -0.40005 0 270)
			(size 0 0)
			(layers "B.Cu" "B.Mask" "B.Paste")
			(net "GND")
		)
	)
	(footprint ""
		(layer "B.Cu")
		(at 47.17288 -385.50088 -90)
		(property "Reference" "C186"
			(at 0 0 90)
			(layer "B.SilkS")
			(hide yes)
			(effects
				(font
					(size 1.27 1.27)
				)
				(justify mirror)
			)
		)
		(property "Value" ""
			(at 0 0 90)
			(layer "B.Fab")
			(effects
				(font
					(size 1.27 1.27)
				)
				(justify mirror)
			)
		)
		(duplicate_pad_numbers_are_jumpers no)
		(fp_line
			(start -0.299974 0.150114)
			(end 0.299974 0.150114)
			(stroke
				(width 0.1)
				(type default)
			)
			(layer "B.Fab")
		)
		(fp_line
			(start 0.299974 0.150114)
			(end 0.299974 -0.150114)
			(stroke
				(width 0.1)
				(type default)
			)
			(layer "B.Fab")
		)
		(fp_line
			(start -0.299974 -0.150114)
			(end -0.299974 0.150114)
			(stroke
				(width 0.1)
				(type default)
			)
			(layer "B.Fab")
		)
		(fp_line
			(start 0.299974 -0.150114)
			(end -0.299974 -0.150114)
			(stroke
				(width 0.1)
				(type default)
			)
			(layer "B.Fab")
		)
		(pad "1" smd rect
			(at 0.2667 0 90)
			(size 0.3048 0.381)
			(layers "B.Cu" "B.Mask" "B.Paste")
			(net "P0V9_CPU1_RT0_2A")
		)
		(pad "2" smd rect
			(at -0.2667 0 90)
			(size 0.3048 0.381)
			(layers "B.Cu" "B.Mask" "B.Paste")
			(net "GND")
		)
	)
	(footprint ""
		(layer "B.Cu")
		(at 363.645958 -259.845048 180)
		(property "Reference" "C2624"
			(at 0 0 0)
			(layer "B.SilkS")
			(hide yes)
			(effects
				(font
					(size 1.27 1.27)
				)
				(justify mirror)
			)
		)
		(property "Value" ""
			(at 0 0 0)
			(layer "B.Fab")
			(effects
				(font
					(size 1.27 1.27)
				)
				(justify mirror)
			)
		)
		(duplicate_pad_numbers_are_jumpers no)
		(fp_line
			(start 0.7874 0.4064)
			(end 0.7874 -0.4064)
			(stroke
				(width 0.1524)
				(type default)
			)
			(layer "B.SilkS")
		)
		(fp_line
			(start 0.7874 -0.4064)
			(end -0.7874 -0.4064)
			(stroke
				(width 0.1524)
				(type default)
			)
			(layer "B.SilkS")
		)
		(fp_line
			(start -0.7874 0.4064)
			(end 0.7874 0.4064)
			(stroke
				(width 0.1524)
				(type default)
			)
			(layer "B.SilkS")
		)
		(fp_line
			(start -0.7874 -0.4064)
			(end -0.7874 0.4064)
			(stroke
				(width 0.1524)
				(type default)
			)
			(layer "B.SilkS")
		)
		(fp_line
			(start 0.67945 0.3048)
			(end 0.67945 -0.305054)
			(stroke
				(width 0.1)
				(type default)
			)
			(layer "B.Fab")
		)
		(fp_line
			(start 0.67945 -0.305054)
			(end 0.12065 -0.305054)
			(stroke
				(width 0.1)
				(type default)
			)
			(layer "B.Fab")
		)
		(fp_line
			(start 0.12065 0.3048)
			(end 0.67945 0.3048)
			(stroke
				(width 0.1)
				(type default)
			)
			(layer "B.Fab")
		)
		(fp_line
			(start 0.12065 0.2794)
			(end 0.12065 0.3048)
			(stroke
				(width 0.1)
				(type default)
			)
			(layer "B.Fab")
		)
		(fp_line
			(start 0.12065 -0.2794)
			(end -0.12065 -0.2794)
			(stroke
				(width 0.1)
				(type default)
			)
			(layer "B.Fab")
		)
		(fp_line
			(start 0.12065 -0.305054)
			(end 0.12065 -0.2794)
			(stroke
				(width 0.1)
				(type default)
			)
			(layer "B.Fab")
		)
		(fp_line
			(start -0.120396 0.3048)
			(end -0.120396 0.2794)
			(stroke
				(width 0.1)
				(type default)
			)
			(layer "B.Fab")
		)
		(fp_line
			(start -0.120396 0.2794)
			(end 0.12065 0.2794)
			(stroke
				(width 0.1)
				(type default)
			)
			(layer "B.Fab")
		)
		(fp_line
			(start -0.12065 -0.2794)
			(end -0.12065 -0.3048)
			(stroke
				(width 0.1)
				(type default)
			)
			(layer "B.Fab")
		)
		(fp_line
			(start -0.12065 -0.3048)
			(end -0.67945 -0.3048)
			(stroke
				(width 0.1)
				(type default)
			)
			(layer "B.Fab")
		)
		(fp_line
			(start -0.67945 0.3048)
			(end -0.120396 0.3048)
			(stroke
				(width 0.1)
				(type default)
			)
			(layer "B.Fab")
		)
		(fp_line
			(start -0.67945 -0.3048)
			(end -0.67945 0.3048)
			(stroke
				(width 0.1)
				(type default)
			)
			(layer "B.Fab")
		)
		(pad "1" smd circle
			(at 0.40005 0)
			(size 0 0)
			(layers "B.Cu" "B.Mask" "B.Paste")
			(net "PVDD11_S3_P0")
		)
		(pad "2" smd circle
			(at -0.40005 0)
			(size 0 0)
			(layers "B.Cu" "B.Mask" "B.Paste")
			(net "GND")
		)
	)
)
